# S9S_MB_2U (Grand Teton) — schematic netlist excerpt (pin names and nets, part order shuffled) for the footprints in the layout excerpt that follows; sources: Cadence DE-HDL packaged netlist, KiCad conversion of 03242023_DA0F0TMBIJ0_F0T_Motherboard_J_brd_V01_OCP.brd

J31  SCONN288_ADR50017P130CC  SCONN288_ADR50017-P130CC IO  pkg DDR288S_1-1VXB  page 112
  VIN_BULK0  = P12V_S3_AUX_CPU1_NVDIMM
  RFU0  = TP_CHH_CPU1_DIMM1_FRU_0
  VIN_MGMT  = P3V3_AUX
  HSCL  = I3C_SPD_DDREFGH_CPU1_LVC1_SCL_6
  HSDA  = I3C_SPD_DDREFGH_CPU1_LVC1_SDA
  VSS0  = GND
  DQ0_A  = M_H_CPU1_SA_DQ<0>
  VSS1  = GND
  DQ1_A  = M_H_CPU1_SA_DQ<1>
  VSS2  = GND
  DQS0_A_T  = M_H_CPU1_SA_DQS_DP<0>
  DQS0_A_C  = M_H_CPU1_SA_DQS_DN<0>
  VSS3  = GND
  DQ4_A  = M_H_CPU1_SA_DQ<4>
  VSS4  = GND
  DQ5_A  = M_H_CPU1_SA_DQ<5>
  VSS5  = GND
  DQ8_A  = M_H_CPU1_SA_DQ<8>
  VSS6  = GND
  DQ9_A  = M_H_CPU1_SA_DQ<9>
  VSS7  = GND
  DQS1_A_T  = M_H_CPU1_SA_DQS_DP<1>
  DQS1_A_C  = M_H_CPU1_SA_DQS_DN<1>
  VSS8  = GND
  DQ12_A  = M_H_CPU1_SA_DQ<12>
  VSS9  = GND
  DQ13_A  = M_H_CPU1_SA_DQ<13>
  VSS10  = GND
  DQ16_A  = M_H_CPU1_SA_DQ<16>
  VSS11  = GND
  DQ17_A  = M_H_CPU1_SA_DQ<17>
  VSS12  = GND
  DQS2_A_T  = M_H_CPU1_SA_DQS_DP<2>
  DQS2_A_C  = M_H_CPU1_SA_DQS_DN<2>
  VSS13  = GND
  DQ20_A  = M_H_CPU1_SA_DQ<20>
  VSS14  = GND
  DQ21_A  = M_H_CPU1_SA_DQ<21>
  VSS15  = GND
  DQ24_A  = M_H_CPU1_SA_DQ<24>
  VSS16  = GND
  DQ25_A  = M_H_CPU1_SA_DQ<25>
  VSS17  = GND
  DQS3_A_T  = M_H_CPU1_SA_DQS_DP<3>
  DQS3_A_C  = M_H_CPU1_SA_DQS_DN<3>
  VSS18  = GND
  DQ28_A  = M_H_CPU1_SA_DQ<28>
  VSS19  = GND
  DQ29_A  = M_H_CPU1_SA_DQ<29>
  VSS20  = GND
  CB0_A  = M_H_CPU1_SA_CB<0>
  VSS21  = GND
  CB1_A  = M_H_CPU1_SA_CB<1>
  VSS22  = GND
  DQS4_A_T  = M_H_CPU1_SA_DQS_DP<4>
  DQS4_A_C  = M_H_CPU1_SA_DQS_DN<4>
  VSS23  = GND
  CB4_A  = M_H_CPU1_SA_CB<4>
  VSS24  = GND
  CB5_A  = M_H_CPU1_SA_CB<5>
  VSS25  = GND
  ALERT_N  = M_H_CPU1_ALERT_N
  VSS26  = GND
  CS0_A_N  = M_H_CPU1_SA_CS_N<0>
  VSS27  = GND
  CA0_A  = M_H_CPU1_SA_CA<0>
  VSS28  = GND
  CA2_A  = M_H_CPU1_SA_CA<2>
  VSS29  = GND
  CA4_A  = M_H_CPU1_SA_CA<4>
  VSS30  = GND
  CA6_A  = M_H_CPU1_SA_CA<6>
  VSS31  = GND
  PAR_A  = M_H_CPU1_SA_PAR
  VSS32  = GND
  CA0_B  = M_H_CPU1_SB_CA<0>
  VSS33  = GND
  CA2_B  = M_H_CPU1_SB_CA<2>
  VSS34  = GND
  CA4_B  = M_H_CPU1_SB_CA<4>
  VSS35  = GND
  CA6_B  = M_H_CPU1_SB_CA<6>
  VSS36  = GND
  CS0_B_N  = M_H_CPU1_SB_CS_N<0>
  VSS37  = GND
  \lbd||rsp_a_n\  = M_H_CPU1_SA_RSP<0>
  \lbs||rsp_b_n\  = M_H_CPU1_SB_RSP<0>
  VSS38  = GND
  CB4_B  = M_H_CPU1_SB_CB<4>
  VSS39  = GND
  CB5_B  = M_H_CPU1_SB_CB<5>
  VSS40  = GND
  \dqs9_b_t||tdqs9_b_t||dbi4_b_n\  = M_H_CPU1_SB_DQS_DP<9>
  \dqs9_b_c||tdqs9_b_c\  = M_H_CPU1_SB_DQS_DN<9>
  VSS41  = GND
  CB0_B  = M_H_CPU1_SB_CB<0>
  VSS42  = GND
  CB1_B  = M_H_CPU1_SB_CB<1>
  VSS43  = GND
  DQ0_B  = M_H_CPU1_SB_DQ<0>
  VSS44  = GND
  DQ1_B  = M_H_CPU1_SB_DQ<1>
  VSS45  = GND
  DQS0_B_T  = M_H_CPU1_SB_DQS_DP<0>
  DQS0_B_C  = M_H_CPU1_SB_DQS_DN<0>
  VSS46  = GND
  DQ4_B  = M_H_CPU1_SB_DQ<4>
  VSS47  = GND
  DQ5_B  = M_H_CPU1_SB_DQ<5>
  VSS48  = GND
  DQ8_B  = M_H_CPU1_SB_DQ<8>
  VSS49  = GND
  DQ9_B  = M_H_CPU1_SB_DQ<9>
  VSS50  = GND
  DQS1_B_T  = M_H_CPU1_SB_DQS_DP<1>
  DQS1_B_C  = M_H_CPU1_SB_DQS_DN<1>
  VSS51  = GND
  DQ12_B  = M_H_CPU1_SB_DQ<12>
  VSS52  = GND
  DQ13_B  = M_H_CPU1_SB_DQ<13>
  VSS53  = GND
  DQ16_B  = M_H_CPU1_SB_DQ<16>
  VSS54  = GND
  DQ17_B  = M_H_CPU1_SB_DQ<17>
  VSS55  = GND
  DQS2_B_T  = M_H_CPU1_SB_DQS_DP<2>
  DQS2_B_C  = M_H_CPU1_SB_DQS_DN<2>
  VSS56  = GND
  DQ20_B  = M_H_CPU1_SB_DQ<20>
  VSS57  = GND
  DQ21_B  = M_H_CPU1_SB_DQ<21>
  VSS58  = GND
  DQ24_B  = M_H_CPU1_SB_DQ<24>
  VSS59  = GND
  DQ25_B  = M_H_CPU1_SB_DQ<25>
  VSS60  = GND
  DQS3_B_T  = M_H_CPU1_SB_DQS_DP<3>
  DQS3_B_C  = M_H_CPU1_SB_DQS_DN<3>
  VSS61  = GND
  DQ28_B  = M_H_CPU1_SB_DQ<28>
  VSS62  = GND
  DQ29_B  = M_H_CPU1_SB_DQ<29>
  VSS63  = GND
  RFU1  = TP_CHH_CPU1_DIMM1_FRU_1
  VIN_BULK1  = P12V_S3_AUX_CPU1_NVDIMM
  VIN_BULK2  = P12V_S3_AUX_CPU1_NVDIMM
  \pwr_good||fail_n\  = PWRGD_CHH_CPU1_DIMM1
  HSA  = PD_CHH_CPU1_DIMM1_SAA
  RFU2  = TP_CHH_CPU1_DIMM1_FRU_2
  RFU3  = TP_CHH_CPU1_DIMM1_FRU_3
  VSS64  = GND
  DQ2_A  = M_H_CPU1_SA_DQ<2>
  VSS65  = GND
  DQ3_A  = M_H_CPU1_SA_DQ<3>
  VSS66  = GND
  \dqs5_a_c||tdqs5_a_c||dqs5_a_t||tdqs5_a_t\  = M_H_CPU1_SA_DQS_DN<5>
  \dqs5_a_t||tdqs5_a_t\  = M_H_CPU1_SA_DQS_DP<5>
  VSS67  = GND
  DQ6_A  = M_H_CPU1_SA_DQ<6>
  VSS68  = GND
  DQ7_A  = M_H_CPU1_SA_DQ<7>
  VSS69  = GND
  DQ10_A  = M_H_CPU1_SA_DQ<10>
  VSS70  = GND
  DQ11_A  = M_H_CPU1_SA_DQ<11>
  VSS71  = GND
  \dqs6_a_c||tdqs6_a_c||dqs6_a_t||tdqs6_a_t\  = M_H_CPU1_SA_DQS_DN<6>
  \dqs6_a_t||tdqs6_a_t\  = M_H_CPU1_SA_DQS_DP<6>
  VSS72  = GND
  DQ14_A  = M_H_CPU1_SA_DQ<14>
  VSS73  = GND
  DQ15_A  = M_H_CPU1_SA_DQ<15>
  VSS74  = GND
  DQ18_A  = M_H_CPU1_SA_DQ<18>
  VSS75  = GND
  DQ19_A  = M_H_CPU1_SA_DQ<19>
  VSS76  = GND
  \dqs7_a_c||tdqs7_a_c\  = M_H_CPU1_SA_DQS_DN<7>
  \dqs7_a_t||tdqs7_a_t\  = M_H_CPU1_SA_DQS_DP<7>
  VSS77  = GND
  DQ22_A  = M_H_CPU1_SA_DQ<22>
  VSS78  = GND
  DQ23_A  = M_H_CPU1_SA_DQ<23>
  VSS79  = GND
  DQ26_A  = M_H_CPU1_SA_DQ<26>
  VSS80  = GND
  DQ27_A  = M_H_CPU1_SA_DQ<27>
  VSS81  = GND
  \dqs8_a_c||tdqs8_a_c\  = M_H_CPU1_SA_DQS_DN<8>
  \dqs8_a_t||tdqs8_a_t\  = M_H_CPU1_SA_DQS_DP<8>
  VSS82  = GND
  DQ30_A  = M_H_CPU1_SA_DQ<30>
  VSS83  = GND
  DQ31_A  = M_H_CPU1_SA_DQ<31>
  VSS84  = GND
  CB2_A  = M_H_CPU1_SA_CB<2>
  VSS85  = GND
  CB3_A  = M_H_CPU1_SA_CB<3>
  VSS86  = GND
  \dqs9_a_c||tdqs9_a_c\  = M_H_CPU1_SA_DQS_DN<9>
  \dqs9_a_t||tdqs9_a_t\  = M_H_CPU1_SA_DQS_DP<9>
  VSS87  = GND
  CB6_A  = M_H_CPU1_SA_CB<6>
  VSS88  = GND
  CB7_A  = M_H_CPU1_SA_CB<7>
  VSS89  = GND
  RESET_N  = RST_M_GH_CPU1_FPGA_N
  VSS90  = GND
  CS1_A_N  = M_H_CPU1_SA_CS_N<1>
  VSS91  = GND
  CA1_A  = M_H_CPU1_SA_CA<1>
  VSS92  = GND
  CA3_A  = M_H_CPU1_SA_CA<3>
  VSS93  = GND
  CA5_A  = M_H_CPU1_SA_CA<5>
  VSS94  = GND
  CK_T  = M_H_CPU1_CLK_DP<0>
  CK_C  = M_H_CPU1_CLK_DN<0>
  VSS95  = GND
  RFU4  = TP_CHH_CPU1_DIMM1_FRU_4
  CA1_B  = M_H_CPU1_SB_CA<1>
  VSS96  = GND
  CA3_B  = M_H_CPU1_SB_CA<3>
  VSS97  = GND
  CA5_B  = M_H_CPU1_SB_CA<5>
  VSS98  = GND
  PAR_B  = M_H_CPU1_SB_PAR
  VSS99  = GND
  CS1_B_N  = M_H_CPU1_SB_CS_N<1>
  VSS100  = GND
  RFU5  = TP_CHH_CPU1_DIMM1_FRU_5
  RFU6  = TP_CHH_CPU1_DIMM1_FRU_6
  VSS101  = GND
  CB6_B  = M_H_CPU1_SB_CB<6>
  VSS102  = GND
  CB7_B  = M_H_CPU1_SB_CB<7>
  VSS103  = GND
  DQS4_B_C  = M_H_CPU1_SB_DQS_DN<4>
  DQS4_B_T  = M_H_CPU1_SB_DQS_DP<4>
  VSS104  = GND
  CB2_B  = M_H_CPU1_SB_CB<2>
  VSS105  = GND
  CB3_B  = M_H_CPU1_SB_CB<3>
  VSS106  = GND
  DQ2_B  = M_H_CPU1_SB_DQ<2>
  VSS107  = GND
  DQ3_B  = M_H_CPU1_SB_DQ<3>
  VSS108  = GND
  \dqs5_b_c||tdqs5_b_c\  = M_H_CPU1_SB_DQS_DN<5>
  \dqs5_b_t||tdqs5_b_t\  = M_H_CPU1_SB_DQS_DP<5>
  VSS109  = GND
  DQ6_B  = M_H_CPU1_SB_DQ<6>
  VSS110  = GND
  DQ7_B  = M_H_CPU1_SB_DQ<7>
  VSS111  = GND
  DQ10_B  = M_H_CPU1_SB_DQ<10>
  VSS112  = GND
  DQ11_B  = M_H_CPU1_SB_DQ<11>
  VSS113  = GND
  \dqs6_b_c||tdqs6_b_c\  = M_H_CPU1_SB_DQS_DN<6>
  \dqs6_b_t||tdqs6_b_t\  = M_H_CPU1_SB_DQS_DP<6>
  VSS114  = GND
  DQ14_B  = M_H_CPU1_SB_DQ<14>
  VSS115  = GND
  DQ15_B  = M_H_CPU1_SB_DQ<15>
  VSS116  = GND
  DQ18_B  = M_H_CPU1_SB_DQ<18>
  VSS117  = GND
  DQ19_B  = M_H_CPU1_SB_DQ<19>
  VSS118  = GND
  \dqs7_b_c||tdqs7_b_c\  = M_H_CPU1_SB_DQS_DN<7>
  \dqs7_b_t||tdqs7_b_t\  = M_H_CPU1_SB_DQS_DP<7>
  VSS119  = GND
  DQ22_B  = M_H_CPU1_SB_DQ<22>
  VSS120  = GND
  DQ23_B  = M_H_CPU1_SB_DQ<23>
  VSS121  = GND
  DQ26_B  = M_H_CPU1_SB_DQ<26>
  VSS122  = GND
  DQ27_B  = M_H_CPU1_SB_DQ<27>
  VSS123  = GND
  \dqs8_b_c||tdqs8_b_c\  = M_H_CPU1_SB_DQS_DN<8>
  \dqs8_b_t||tdqs8_b_t\  = M_H_CPU1_SB_DQS_DP<8>
  VSS124  = GND
  DQ30_B  = M_H_CPU1_SB_DQ<30>
  VSS125  = GND
  DQ31_B  = M_H_CPU1_SB_DQ<31>
  VSS126  = GND
  G1  = GND
  G2  = GND
  G3  = GND

(kicad_pcb
	(version 20260206)
	(generator "pcbnew")
	(generator_version "10.0")
	(general
		(thickness 1.6)
		(legacy_teardrops no)
	)
	(paper "A4")
	(title_block
		(title "03242023_DA0F0TMBIJ0_F0T_Motherboard_J_brd_V01_OCP.brd")
		(comment 1 "Grand Teton / footprint 3900 of 6105 (J31), pads 46-91 of 291")
	)
	(layers
		(0 "F.Cu" signal "TOP")
		(4 "In1.Cu" signal "GND")
		(6 "In2.Cu" signal "IN1")
		(8 "In3.Cu" signal "GND1")
		(10 "In4.Cu" signal "IN2")
		(12 "In5.Cu" signal "GND2")
		(14 "In6.Cu" signal "IN3")
		(16 "In7.Cu" signal "GND3")
		(18 "In8.Cu" signal "VCC")
		(20 "In9.Cu" signal "VCC1")
		(22 "In10.Cu" signal "GND4")
		(24 "In11.Cu" signal "IN4")
		(26 "In12.Cu" signal "GND5")
		(28 "In13.Cu" signal "IN5")
		(30 "In14.Cu" signal "GND6")
		(32 "In15.Cu" signal "IN6")
		(34 "In16.Cu" signal "GND7")
		(2 "B.Cu" signal "BOTTOM")
		(9 "F.Adhes" user "F.Adhesive")
		(11 "B.Adhes" user "B.Adhesive")
		(13 "F.Paste" user "Package Geometry/Pastemask Top")
		(15 "B.Paste" user "Package Geometry/Pastemask Bottom")
		(5 "F.SilkS" user "Ref Des/Silkscreen Top")
		(7 "B.SilkS" user "Ref Des/Silkscreen Bottom")
		(1 "F.Mask" user "Board Geometry/Soldermask Top")
		(3 "B.Mask" user "Board Geometry/Soldermask Bottom")
		(17 "Dwgs.User" user "User.Drawings")
		(19 "Cmts.User" user "User.Comments")
		(21 "Eco1.User" user "User.Eco1")
		(23 "Eco2.User" user "User.Eco2")
		(25 "Edge.Cuts" user "Board Geometry/Outline")
		(27 "Margin" user)
		(31 "F.CrtYd" user "Package Geometry/Place Bound Top")
		(29 "B.CrtYd" user "Package Geometry/Place Bound Bottom")
		(35 "F.Fab" user "Ref Des/Assembly Top")
		(33 "B.Fab" user "Ref Des/Assembly Bottom")
	)
	(footprint ""
		(layer "F.Cu")
		(at 213.66988 -258.091686)
		(property "Reference" "J31"
			(at -3.683 -81.702148 0)
			(unlocked yes)
			(layer "F.SilkS")
			(effects
				(font
					(size 0.7874 0.5842)
					(thickness 0.1524)
				)
				(justify left)
			)
		)
		(property "Value" ""
			(at 0 0 0)
			(layer "F.Fab")
			(effects
				(font
					(size 1.27 1.27)
				)
			)
		)
		(duplicate_pad_numbers_are_jumpers no)
		(pad "46" smd rect
			(at -2.050034 -25.07488 270)
			(size 0.519938 1.4986)
			(layers "F.Cu" "F.Mask" "F.Paste")
			(net "GND")
		)
		(pad "47" smd rect
			(at -2.050034 -24.224996 270)
			(size 0.519938 1.4986)
			(layers "F.Cu" "F.Mask" "F.Paste")
			(net "M_H_CPU1_SA_DQ<28>")
		)
		(pad "48" smd rect
			(at -2.050034 -23.375112 270)
			(size 0.519938 1.4986)
			(layers "F.Cu" "F.Mask" "F.Paste")
			(net "GND")
		)
		(pad "49" smd rect
			(at -2.050034 -22.524974 270)
			(size 0.519938 1.4986)
			(layers "F.Cu" "F.Mask" "F.Paste")
			(net "M_H_CPU1_SA_DQ<29>")
		)
		(pad "50" smd rect
			(at -2.050034 -21.67509 270)
			(size 0.519938 1.4986)
			(layers "F.Cu" "F.Mask" "F.Paste")
			(net "GND")
		)
		(pad "51" smd rect
			(at -2.050034 -20.824952 270)
			(size 0.519938 1.4986)
			(layers "F.Cu" "F.Mask" "F.Paste")
			(net "M_H_CPU1_SA_CB<0>")
		)
		(pad "52" smd rect
			(at -2.050034 -19.975068 270)
			(size 0.519938 1.4986)
			(layers "F.Cu" "F.Mask" "F.Paste")
			(net "GND")
		)
		(pad "53" smd rect
			(at -2.050034 -19.12493 270)
			(size 0.519938 1.4986)
			(layers "F.Cu" "F.Mask" "F.Paste")
			(net "M_H_CPU1_SA_CB<1>")
		)
		(pad "54" smd rect
			(at -2.050034 -18.275046 270)
			(size 0.519938 1.4986)
			(layers "F.Cu" "F.Mask" "F.Paste")
			(net "GND")
		)
		(pad "55" smd rect
			(at -2.050034 -17.424908 270)
			(size 0.519938 1.4986)
			(layers "F.Cu" "F.Mask" "F.Paste")
			(net "M_H_CPU1_SA_DQS_DP<4>")
		)
		(pad "56" smd rect
			(at -2.050034 -16.575024 270)
			(size 0.519938 1.4986)
			(layers "F.Cu" "F.Mask" "F.Paste")
			(net "M_H_CPU1_SA_DQS_DN<4>")
		)
		(pad "57" smd rect
			(at -2.050034 -15.724886 270)
			(size 0.519938 1.4986)
			(layers "F.Cu" "F.Mask" "F.Paste")
			(net "GND")
		)
		(pad "58" smd rect
			(at -2.050034 -14.875002 270)
			(size 0.519938 1.4986)
			(layers "F.Cu" "F.Mask" "F.Paste")
			(net "M_H_CPU1_SA_CB<4>")
		)
		(pad "59" smd rect
			(at -2.050034 -14.025118 270)
			(size 0.519938 1.4986)
			(layers "F.Cu" "F.Mask" "F.Paste")
			(net "GND")
		)
		(pad "60" smd rect
			(at -2.050034 -13.17498 270)
			(size 0.519938 1.4986)
			(layers "F.Cu" "F.Mask" "F.Paste")
			(net "M_H_CPU1_SA_CB<5>")
		)
		(pad "61" smd rect
			(at -2.050034 -12.325096 270)
			(size 0.519938 1.4986)
			(layers "F.Cu" "F.Mask" "F.Paste")
			(net "GND")
		)
		(pad "62" smd rect
			(at -2.050034 -11.474958 270)
			(size 0.519938 1.4986)
			(layers "F.Cu" "F.Mask" "F.Paste")
			(net "M_H_CPU1_ALERT_N")
		)
		(pad "63" smd rect
			(at -2.050034 -10.625074 270)
			(size 0.519938 1.4986)
			(layers "F.Cu" "F.Mask" "F.Paste")
			(net "GND")
		)
		(pad "64" smd rect
			(at -2.050034 -9.774936 270)
			(size 0.519938 1.4986)
			(layers "F.Cu" "F.Mask" "F.Paste")
			(net "M_H_CPU1_SA_CS_N<0>")
		)
		(pad "65" smd rect
			(at -2.050034 -8.925052 270)
			(size 0.519938 1.4986)
			(layers "F.Cu" "F.Mask" "F.Paste")
			(net "GND")
		)
		(pad "66" smd rect
			(at -2.050034 -8.074914 270)
			(size 0.519938 1.4986)
			(layers "F.Cu" "F.Mask" "F.Paste")
			(net "M_H_CPU1_SA_CA<0>")
		)
		(pad "67" smd rect
			(at -2.050034 -7.22503 270)
			(size 0.519938 1.4986)
			(layers "F.Cu" "F.Mask" "F.Paste")
			(net "GND")
		)
		(pad "68" smd rect
			(at -2.050034 -6.374892 270)
			(size 0.519938 1.4986)
			(layers "F.Cu" "F.Mask" "F.Paste")
			(net "M_H_CPU1_SA_CA<2>")
		)
		(pad "69" smd rect
			(at -2.050034 -5.525008 270)
			(size 0.519938 1.4986)
			(layers "F.Cu" "F.Mask" "F.Paste")
			(net "GND")
		)
		(pad "70" smd rect
			(at -2.050034 -4.675124 270)
			(size 0.519938 1.4986)
			(layers "F.Cu" "F.Mask" "F.Paste")
			(net "M_H_CPU1_SA_CA<4>")
		)
		(pad "71" smd rect
			(at -2.050034 -3.824986 270)
			(size 0.519938 1.4986)
			(layers "F.Cu" "F.Mask" "F.Paste")
			(net "GND")
		)
		(pad "72" smd rect
			(at -2.050034 -2.975102 270)
			(size 0.519938 1.4986)
			(layers "F.Cu" "F.Mask" "F.Paste")
			(net "M_H_CPU1_SA_CA<6>")
		)
		(pad "73" smd rect
			(at -2.050034 -2.124964 270)
			(size 0.519938 1.4986)
			(layers "F.Cu" "F.Mask" "F.Paste")
			(net "GND")
		)
		(pad "74" smd rect
			(at -2.050034 -1.27508 270)
			(size 0.519938 1.4986)
			(layers "F.Cu" "F.Mask" "F.Paste")
			(net "M_H_CPU1_SA_PAR")
		)
		(pad "75" smd rect
			(at -2.050034 -0.424942 270)
			(size 0.519938 1.4986)
			(layers "F.Cu" "F.Mask" "F.Paste")
			(net "GND")
		)
		(pad "76" smd rect
			(at -2.050034 5.525008 270)
			(size 0.519938 1.4986)
			(layers "F.Cu" "F.Mask" "F.Paste")
			(net "M_H_CPU1_SB_CA<0>")
		)
		(pad "77" smd rect
			(at -2.050034 6.374892 270)
			(size 0.519938 1.4986)
			(layers "F.Cu" "F.Mask" "F.Paste")
			(net "GND")
		)
		(pad "78" smd rect
			(at -2.050034 7.22503 270)
			(size 0.519938 1.4986)
			(layers "F.Cu" "F.Mask" "F.Paste")
			(net "M_H_CPU1_SB_CA<2>")
		)
		(pad "79" smd rect
			(at -2.050034 8.074914 270)
			(size 0.519938 1.4986)
			(layers "F.Cu" "F.Mask" "F.Paste")
			(net "GND")
		)
		(pad "80" smd rect
			(at -2.050034 8.925052 270)
			(size 0.519938 1.4986)
			(layers "F.Cu" "F.Mask" "F.Paste")
			(net "M_H_CPU1_SB_CA<4>")
		)
		(pad "81" smd rect
			(at -2.050034 9.774936 270)
			(size 0.519938 1.4986)
			(layers "F.Cu" "F.Mask" "F.Paste")
			(net "GND")
		)
		(pad "82" smd rect
			(at -2.050034 10.625074 270)
			(size 0.519938 1.4986)
			(layers "F.Cu" "F.Mask" "F.Paste")
			(net "M_H_CPU1_SB_CA<6>")
		)
		(pad "83" smd rect
			(at -2.050034 11.474958 270)
			(size 0.519938 1.4986)
			(layers "F.Cu" "F.Mask" "F.Paste")
			(net "GND")
		)
		(pad "84" smd rect
			(at -2.050034 12.325096 270)
			(size 0.519938 1.4986)
			(layers "F.Cu" "F.Mask" "F.Paste")
			(net "M_H_CPU1_SB_CS_N<0>")
		)
		(pad "85" smd rect
			(at -2.050034 13.17498 270)
			(size 0.519938 1.4986)
			(layers "F.Cu" "F.Mask" "F.Paste")
			(net "GND")
		)
		(pad "86" smd rect
			(at -2.050034 14.025118 270)
			(size 0.519938 1.4986)
			(layers "F.Cu" "F.Mask" "F.Paste")
			(net "M_H_CPU1_SA_RSP<0>")
		)
		(pad "87" smd rect
			(at -2.050034 14.875002 270)
			(size 0.519938 1.4986)
			(layers "F.Cu" "F.Mask" "F.Paste")
			(net "M_H_CPU1_SB_RSP<0>")
		)
		(pad "88" smd rect
			(at -2.050034 15.724886 270)
			(size 0.519938 1.4986)
			(layers "F.Cu" "F.Mask" "F.Paste")
			(net "GND")
		)
		(pad "89" smd rect
			(at -2.050034 16.575024 270)
			(size 0.519938 1.4986)
			(layers "F.Cu" "F.Mask" "F.Paste")
			(net "M_H_CPU1_SB_CB<4>")
		)
		(pad "90" smd rect
			(at -2.050034 17.424908 270)
			(size 0.519938 1.4986)
			(layers "F.Cu" "F.Mask" "F.Paste")
			(net "GND")
		)
		(pad "91" smd rect
			(at -2.050034 18.275046 270)
			(size 0.519938 1.4986)
			(layers "F.Cu" "F.Mask" "F.Paste")
			(net "M_H_CPU1_SB_CB<5>")
		)
	)
)
